# S9S_MB_2U (Grand Teton) — schematic netlist excerpt (pin names and nets, part order shuffled) for the footprints in the layout excerpt that follows; sources: Cadence DE-HDL packaged netlist, KiCad conversion of 03242023_DA0F0TMBIJ0_F0T_Motherboard_J_brd_V01_OCP.brd

C83  Q_CAP  10UF 16V 10% X6S  pkg C0805  page 110 : A = P12V_S3_AUX_CPU1_NVDIMM ; B = GND
C350  Q_CAP  47UF 4V 20% X6S  pkg C0805  page 79 : A = PVCCIN_CPU1 ; B = GND
C1437  Q_CAP  0.22UF 6.3V 10% X6S  pkg C0201  page 78 : A = PVPP_HBM_CPU1 ; B = GND
R39  Q_RES  84.5K 1% CHIP  pkg 0402LF  page 95 : A = PD_CHG_CPU0_DIMM2_SAA ; B = GND

(kicad_pcb
	(version 20260206)
	(generator "pcbnew")
	(generator_version "10.0")
	(general
		(thickness 1.6)
		(legacy_teardrops no)
	)
	(paper "A4")
	(title_block
		(title "03242023_DA0F0TMBIJ0_F0T_Motherboard_J_brd_V01_OCP.brd")
		(comment 1 "Grand Teton / footprints 5521-5524 of 6105")
	)
	(layers
		(0 "F.Cu" signal "TOP")
		(4 "In1.Cu" signal "GND")
		(6 "In2.Cu" signal "IN1")
		(8 "In3.Cu" signal "GND1")
		(10 "In4.Cu" signal "IN2")
		(12 "In5.Cu" signal "GND2")
		(14 "In6.Cu" signal "IN3")
		(16 "In7.Cu" signal "GND3")
		(18 "In8.Cu" signal "VCC")
		(20 "In9.Cu" signal "VCC1")
		(22 "In10.Cu" signal "GND4")
		(24 "In11.Cu" signal "IN4")
		(26 "In12.Cu" signal "GND5")
		(28 "In13.Cu" signal "IN5")
		(30 "In14.Cu" signal "GND6")
		(32 "In15.Cu" signal "IN6")
		(34 "In16.Cu" signal "GND7")
		(2 "B.Cu" signal "BOTTOM")
		(9 "F.Adhes" user "F.Adhesive")
		(11 "B.Adhes" user "B.Adhesive")
		(13 "F.Paste" user "Package Geometry/Pastemask Top")
		(15 "B.Paste" user "Package Geometry/Pastemask Bottom")
		(5 "F.SilkS" user "Ref Des/Silkscreen Top")
		(7 "B.SilkS" user "Ref Des/Silkscreen Bottom")
		(1 "F.Mask" user "Board Geometry/Soldermask Top")
		(3 "B.Mask" user "Board Geometry/Soldermask Bottom")
		(17 "Dwgs.User" user "User.Drawings")
		(19 "Cmts.User" user "User.Comments")
		(21 "Eco1.User" user "User.Eco1")
		(23 "Eco2.User" user "User.Eco2")
		(25 "Edge.Cuts" user "Board Geometry/Outline")
		(27 "Margin" user)
		(31 "F.CrtYd" user "Package Geometry/Place Bound Top")
		(29 "B.CrtYd" user "Package Geometry/Place Bound Bottom")
		(35 "F.Fab" user "Ref Des/Assembly Top")
		(33 "B.Fab" user "Ref Des/Assembly Bottom")
	)
	(footprint ""
		(layer "B.Cu")
		(at 143.748252 -334.334866)
		(property "Reference" "C1437"
			(at 0 0 0)
			(layer "B.SilkS")
			(hide yes)
			(effects
				(font
					(size 1.27 1.27)
				)
				(justify mirror)
			)
		)
		(property "Value" ""
			(at 0 0 0)
			(layer "B.Fab")
			(effects
				(font
					(size 1.27 1.27)
				)
				(justify mirror)
			)
		)
		(duplicate_pad_numbers_are_jumpers no)
		(fp_line
			(start -0.299974 -0.150114)
			(end -0.299974 0.150114)
			(stroke
				(width 0.1)
				(type default)
			)
			(layer "B.Fab")
		)
		(fp_line
			(start -0.299974 0.150114)
			(end 0.299974 0.150114)
			(stroke
				(width 0.1)
				(type default)
			)
			(layer "B.Fab")
		)
		(fp_line
			(start 0.299974 -0.150114)
			(end -0.299974 -0.150114)
			(stroke
				(width 0.1)
				(type default)
			)
			(layer "B.Fab")
		)
		(fp_line
			(start 0.299974 0.150114)
			(end 0.299974 -0.150114)
			(stroke
				(width 0.1)
				(type default)
			)
			(layer "B.Fab")
		)
		(pad "1" smd rect
			(at 0.2667 0 180)
			(size 0.3048 0.381)
			(layers "B.Cu" "B.Mask" "B.Paste")
			(net "PVPP_HBM_CPU1")
		)
		(pad "2" smd rect
			(at -0.2667 0 180)
			(size 0.3048 0.381)
			(layers "B.Cu" "B.Mask" "B.Paste")
			(net "GND")
		)
	)
	(footprint ""
		(layer "B.Cu")
		(at 438.686956 -318.603376)
		(property "Reference" "R39"
			(at 0 0 0)
			(layer "B.SilkS")
			(hide yes)
			(effects
				(font
					(size 1.27 1.27)
				)
				(justify mirror)
			)
		)
		(property "Value" ""
			(at 0 0 0)
			(layer "B.Fab")
			(effects
				(font
					(size 1.27 1.27)
				)
				(justify mirror)
			)
		)
		(duplicate_pad_numbers_are_jumpers no)
		(fp_line
			(start -0.7874 -0.4064)
			(end -0.7874 0.4064)
			(stroke
				(width 0.1524)
				(type default)
			)
			(layer "B.SilkS")
		)
		(fp_line
			(start -0.7874 0.4064)
			(end 0.7874 0.4064)
			(stroke
				(width 0.1524)
				(type default)
			)
			(layer "B.SilkS")
		)
		(fp_line
			(start 0.7874 -0.4064)
			(end -0.7874 -0.4064)
			(stroke
				(width 0.1524)
				(type default)
			)
			(layer "B.SilkS")
		)
		(fp_line
			(start 0.7874 0.4064)
			(end 0.7874 -0.4064)
			(stroke
				(width 0.1524)
				(type default)
			)
			(layer "B.SilkS")
		)
		(fp_line
			(start -0.67945 -0.3048)
			(end -0.67945 0.3048)
			(stroke
				(width 0.1)
				(type default)
			)
			(layer "B.Fab")
		)
		(fp_line
			(start -0.67945 0.3048)
			(end -0.120396 0.3048)
			(stroke
				(width 0.1)
				(type default)
			)
			(layer "B.Fab")
		)
		(fp_line
			(start -0.12065 -0.3048)
			(end -0.67945 -0.3048)
			(stroke
				(width 0.1)
				(type default)
			)
			(layer "B.Fab")
		)
		(fp_line
			(start -0.12065 -0.2794)
			(end -0.12065 -0.3048)
			(stroke
				(width 0.1)
				(type default)
			)
			(layer "B.Fab")
		)
		(fp_line
			(start -0.120396 0.2794)
			(end 0.12065 0.2794)
			(stroke
				(width 0.1)
				(type default)
			)
			(layer "B.Fab")
		)
		(fp_line
			(start -0.120396 0.3048)
			(end -0.120396 0.2794)
			(stroke
				(width 0.1)
				(type default)
			)
			(layer "B.Fab")
		)
		(fp_line
			(start 0.12065 -0.305054)
			(end 0.12065 -0.2794)
			(stroke
				(width 0.1)
				(type default)
			)
			(layer "B.Fab")
		)
		(fp_line
			(start 0.12065 -0.2794)
			(end -0.12065 -0.2794)
			(stroke
				(width 0.1)
				(type default)
			)
			(layer "B.Fab")
		)
		(fp_line
			(start 0.12065 0.2794)
			(end 0.12065 0.3048)
			(stroke
				(width 0.1)
				(type default)
			)
			(layer "B.Fab")
		)
		(fp_line
			(start 0.12065 0.3048)
			(end 0.67945 0.3048)
			(stroke
				(width 0.1)
				(type default)
			)
			(layer "B.Fab")
		)
		(fp_line
			(start 0.67945 -0.305054)
			(end 0.12065 -0.305054)
			(stroke
				(width 0.1)
				(type default)
			)
			(layer "B.Fab")
		)
		(fp_line
			(start 0.67945 0.3048)
			(end 0.67945 -0.305054)
			(stroke
				(width 0.1)
				(type default)
			)
			(layer "B.Fab")
		)
		(pad "1" smd circle
			(at 0.40005 0 180)
			(size 0 0)
			(layers "B.Cu" "B.Mask" "B.Paste")
			(net "PD_CHG_CPU0_DIMM2_SAA")
		)
		(pad "2" smd circle
			(at -0.40005 0 180)
			(size 0 0)
			(layers "B.Cu" "B.Mask" "B.Paste")
			(net "GND")
		)
	)
	(footprint ""
		(layer "B.Cu")
		(at 115.195604 -296.05478 180)
		(property "Reference" "C350"
			(at 0 0 0)
			(layer "B.SilkS")
			(hide yes)
			(effects
				(font
					(size 1.27 1.27)
				)
				(justify mirror)
			)
		)
		(property "Value" ""
			(at 0 0 0)
			(layer "B.Fab")
			(effects
				(font
					(size 1.27 1.27)
				)
				(justify mirror)
			)
		)
		(duplicate_pad_numbers_are_jumpers no)
		(fp_line
			(start 1.524 0.762)
			(end 1.524 -0.762)
			(stroke
				(width 0.1524)
				(type default)
			)
			(layer "B.SilkS")
		)
		(fp_line
			(start 1.524 -0.762)
			(end -1.524 -0.762)
			(stroke
				(width 0.1524)
				(type default)
			)
			(layer "B.SilkS")
		)
		(fp_line
			(start -1.524 0.762)
			(end 1.524 0.762)
			(stroke
				(width 0.1524)
				(type default)
			)
			(layer "B.SilkS")
		)
		(fp_line
			(start -1.524 -0.762)
			(end -1.524 0.762)
			(stroke
				(width 0.1524)
				(type default)
			)
			(layer "B.SilkS")
		)
		(fp_line
			(start 1.1049 0.724916)
			(end -1.1049 0.724916)
			(stroke
				(width 0.1)
				(type default)
			)
			(layer "B.Fab")
		)
		(fp_line
			(start 1.1049 -0.724916)
			(end 1.1049 0.724916)
			(stroke
				(width 0.1)
				(type default)
			)
			(layer "B.Fab")
		)
		(fp_line
			(start -1.1049 0.724916)
			(end -1.1049 -0.724916)
			(stroke
				(width 0.1)
				(type default)
			)
			(layer "B.Fab")
		)
		(fp_line
			(start -1.1049 -0.724916)
			(end 1.1049 -0.724916)
			(stroke
				(width 0.1)
				(type default)
			)
			(layer "B.Fab")
		)
		(pad "1" smd rect
			(at 0.889 0 180)
			(size 1.016 1.27)
			(layers "B.Cu" "B.Mask" "B.Paste")
			(net "PVCCIN_CPU1")
		)
		(pad "2" smd rect
			(at -0.889 0 180)
			(size 1.016 1.27)
			(layers "B.Cu" "B.Mask" "B.Paste")
			(net "GND")
		)
	)
	(footprint ""
		(layer "B.Cu")
		(at 200.608946 -321.554856 -90)
		(property "Reference" "C83"
			(at 0 0 90)
			(layer "B.SilkS")
			(hide yes)
			(effects
				(font
					(size 1.27 1.27)
				)
				(justify mirror)
			)
		)
		(property "Value" ""
			(at 0 0 90)
			(layer "B.Fab")
			(effects
				(font
					(size 1.27 1.27)
				)
				(justify mirror)
			)
		)
		(duplicate_pad_numbers_are_jumpers no)
		(fp_line
			(start -1.524 0.762)
			(end 1.524 0.762)
			(stroke
				(width 0.1524)
				(type default)
			)
			(layer "B.SilkS")
		)
		(fp_line
			(start 1.524 0.762)
			(end 1.524 -0.762)
			(stroke
				(width 0.1524)
				(type default)
			)
			(layer "B.SilkS")
		)
		(fp_line
			(start -1.524 -0.762)
			(end -1.524 0.762)
			(stroke
				(width 0.1524)
				(type default)
			)
			(layer "B.SilkS")
		)
		(fp_line
			(start 1.524 -0.762)
			(end -1.524 -0.762)
			(stroke
				(width 0.1524)
				(type default)
			)
			(layer "B.SilkS")
		)
		(fp_line
			(start -1.1049 0.724916)
			(end -1.1049 -0.724916)
			(stroke
				(width 0.1)
				(type default)
			)
			(layer "B.Fab")
		)
		(fp_line
			(start 1.1049 0.724916)
			(end -1.1049 0.724916)
			(stroke
				(width 0.1)
				(type default)
			)
			(layer "B.Fab")
		)
		(fp_line
			(start -1.1049 -0.724916)
			(end 1.1049 -0.724916)
			(stroke
				(width 0.1)
				(type default)
			)
			(layer "B.Fab")
		)
		(fp_line
			(start 1.1049 -0.724916)
			(end 1.1049 0.724916)
			(stroke
				(width 0.1)
				(type default)
			)
			(layer "B.Fab")
		)
		(pad "1" smd rect
			(at 0.889 0 270)
			(size 1.016 1.27)
			(layers "B.Cu" "B.Mask" "B.Paste")
			(net "P12V_S3_AUX_CPU1_NVDIMM")
		)
		(pad "2" smd rect
			(at -0.889 0 270)
			(size 1.016 1.27)
			(layers "B.Cu" "B.Mask" "B.Paste")
			(net "GND")
		)
	)
)
